# S9S_MB_2U (Grand Teton) — schematic netlist excerpt (pin names and nets, part order shuffled) for the footprints in the layout excerpt that follows; sources: Cadence DE-HDL packaged netlist, KiCad conversion of 03242023_DA0F0TMBIJ0_F0T_Motherboard_J_brd_V01_OCP.brd

C8  Q_CAP  2.2UF 6.3V 20% X6S  pkg C0402  page 84 : A = P3V3_AUX ; B = GND
R4116  Q_RES  10K 1% CHIP  pkg 0402LF  page 184 : A = PD_PCH_GPP_E_8 ; B = GND

(kicad_pcb
	(version 20260206)
	(generator "pcbnew")
	(generator_version "10.0")
	(general
		(thickness 1.6)
		(legacy_teardrops no)
	)
	(paper "A4")
	(title_block
		(title "03242023_DA0F0TMBIJ0_F0T_Motherboard_J_brd_V01_OCP.brd")
		(comment 1 "Grand Teton / footprints 4611-4612 of 6105")
	)
	(layers
		(0 "F.Cu" signal "TOP")
		(4 "In1.Cu" signal "GND")
		(6 "In2.Cu" signal "IN1")
		(8 "In3.Cu" signal "GND1")
		(10 "In4.Cu" signal "IN2")
		(12 "In5.Cu" signal "GND2")
		(14 "In6.Cu" signal "IN3")
		(16 "In7.Cu" signal "GND3")
		(18 "In8.Cu" signal "VCC")
		(20 "In9.Cu" signal "VCC1")
		(22 "In10.Cu" signal "GND4")
		(24 "In11.Cu" signal "IN4")
		(26 "In12.Cu" signal "GND5")
		(28 "In13.Cu" signal "IN5")
		(30 "In14.Cu" signal "GND6")
		(32 "In15.Cu" signal "IN6")
		(34 "In16.Cu" signal "GND7")
		(2 "B.Cu" signal "BOTTOM")
		(9 "F.Adhes" user "F.Adhesive")
		(11 "B.Adhes" user "B.Adhesive")
		(13 "F.Paste" user "Package Geometry/Pastemask Top")
		(15 "B.Paste" user "Package Geometry/Pastemask Bottom")
		(5 "F.SilkS" user "Ref Des/Silkscreen Top")
		(7 "B.SilkS" user "Ref Des/Silkscreen Bottom")
		(1 "F.Mask" user "Board Geometry/Soldermask Top")
		(3 "B.Mask" user "Board Geometry/Soldermask Bottom")
		(17 "Dwgs.User" user "User.Drawings")
		(19 "Cmts.User" user "User.Comments")
		(21 "Eco1.User" user "User.Eco1")
		(23 "Eco2.User" user "User.Eco2")
		(25 "Edge.Cuts" user "Board Geometry/Outline")
		(27 "Margin" user)
		(31 "F.CrtYd" user "Package Geometry/Place Bound Top")
		(29 "B.CrtYd" user "Package Geometry/Place Bound Bottom")
		(35 "F.Fab" user "Ref Des/Assembly Top")
		(33 "B.Fab" user "Ref Des/Assembly Bottom")
	)
	(footprint ""
		(layer "B.Cu")
		(at 369.49888 -44.160948 180)
		(property "Reference" "R4116"
			(at 0 0 0)
			(layer "B.SilkS")
			(hide yes)
			(effects
				(font
					(size 1.27 1.27)
				)
				(justify mirror)
			)
		)
		(property "Value" ""
			(at 0 0 0)
			(layer "B.Fab")
			(effects
				(font
					(size 1.27 1.27)
				)
				(justify mirror)
			)
		)
		(duplicate_pad_numbers_are_jumpers no)
		(fp_line
			(start 0.7874 0.4064)
			(end 0.7874 -0.4064)
			(stroke
				(width 0.1524)
				(type default)
			)
			(layer "B.SilkS")
		)
		(fp_line
			(start 0.7874 -0.4064)
			(end -0.7874 -0.4064)
			(stroke
				(width 0.1524)
				(type default)
			)
			(layer "B.SilkS")
		)
		(fp_line
			(start -0.7874 0.4064)
			(end 0.7874 0.4064)
			(stroke
				(width 0.1524)
				(type default)
			)
			(layer "B.SilkS")
		)
		(fp_line
			(start -0.7874 -0.4064)
			(end -0.7874 0.4064)
			(stroke
				(width 0.1524)
				(type default)
			)
			(layer "B.SilkS")
		)
		(fp_line
			(start 0.67945 0.3048)
			(end 0.67945 -0.305054)
			(stroke
				(width 0.1)
				(type default)
			)
			(layer "B.Fab")
		)
		(fp_line
			(start 0.67945 -0.305054)
			(end 0.12065 -0.305054)
			(stroke
				(width 0.1)
				(type default)
			)
			(layer "B.Fab")
		)
		(fp_line
			(start 0.12065 0.3048)
			(end 0.67945 0.3048)
			(stroke
				(width 0.1)
				(type default)
			)
			(layer "B.Fab")
		)
		(fp_line
			(start 0.12065 0.2794)
			(end 0.12065 0.3048)
			(stroke
				(width 0.1)
				(type default)
			)
			(layer "B.Fab")
		)
		(fp_line
			(start 0.12065 -0.2794)
			(end -0.12065 -0.2794)
			(stroke
				(width 0.1)
				(type default)
			)
			(layer "B.Fab")
		)
		(fp_line
			(start 0.12065 -0.305054)
			(end 0.12065 -0.2794)
			(stroke
				(width 0.1)
				(type default)
			)
			(layer "B.Fab")
		)
		(fp_line
			(start -0.120396 0.3048)
			(end -0.120396 0.2794)
			(stroke
				(width 0.1)
				(type default)
			)
			(layer "B.Fab")
		)
		(fp_line
			(start -0.120396 0.2794)
			(end 0.12065 0.2794)
			(stroke
				(width 0.1)
				(type default)
			)
			(layer "B.Fab")
		)
		(fp_line
			(start -0.12065 -0.2794)
			(end -0.12065 -0.3048)
			(stroke
				(width 0.1)
				(type default)
			)
			(layer "B.Fab")
		)
		(fp_line
			(start -0.12065 -0.3048)
			(end -0.67945 -0.3048)
			(stroke
				(width 0.1)
				(type default)
			)
			(layer "B.Fab")
		)
		(fp_line
			(start -0.67945 0.3048)
			(end -0.120396 0.3048)
			(stroke
				(width 0.1)
				(type default)
			)
			(layer "B.Fab")
		)
		(fp_line
			(start -0.67945 -0.3048)
			(end -0.67945 0.3048)
			(stroke
				(width 0.1)
				(type default)
			)
			(layer "B.Fab")
		)
		(pad "1" smd circle
			(at 0.40005 0)
			(size 0 0)
			(layers "B.Cu" "B.Mask" "B.Paste")
			(net "PD_PCH_GPP_E_8")
		)
		(pad "2" smd circle
			(at -0.40005 0)
			(size 0 0)
			(layers "B.Cu" "B.Mask" "B.Paste")
			(net "GND")
		)
	)
	(footprint ""
		(layer "B.Cu")
		(at 286.268414 -319.263776 180)
		(property "Reference" "C8"
			(at 0 0 0)
			(layer "B.SilkS")
			(hide yes)
			(effects
				(font
					(size 1.27 1.27)
				)
				(justify mirror)
			)
		)
		(property "Value" ""
			(at 0 0 0)
			(layer "B.Fab")
			(effects
				(font
					(size 1.27 1.27)
				)
				(justify mirror)
			)
		)
		(duplicate_pad_numbers_are_jumpers no)
		(fp_line
			(start 0.7874 0.4064)
			(end 0.7874 -0.4064)
			(stroke
				(width 0.1524)
				(type default)
			)
			(layer "B.SilkS")
		)
		(fp_line
			(start 0.7874 -0.4064)
			(end -0.7874 -0.4064)
			(stroke
				(width 0.1524)
				(type default)
			)
			(layer "B.SilkS")
		)
		(fp_line
			(start -0.7874 0.4064)
			(end 0.7874 0.4064)
			(stroke
				(width 0.1524)
				(type default)
			)
			(layer "B.SilkS")
		)
		(fp_line
			(start -0.7874 -0.4064)
			(end -0.7874 0.4064)
			(stroke
				(width 0.1524)
				(type default)
			)
			(layer "B.SilkS")
		)
		(fp_line
			(start 0.67945 0.3048)
			(end 0.67945 -0.305054)
			(stroke
				(width 0.1)
				(type default)
			)
			(layer "B.Fab")
		)
		(fp_line
			(start 0.67945 -0.305054)
			(end 0.12065 -0.305054)
			(stroke
				(width 0.1)
				(type default)
			)
			(layer "B.Fab")
		)
		(fp_line
			(start 0.12065 0.3048)
			(end 0.67945 0.3048)
			(stroke
				(width 0.1)
				(type default)
			)
			(layer "B.Fab")
		)
		(fp_line
			(start 0.12065 0.2794)
			(end 0.12065 0.3048)
			(stroke
				(width 0.1)
				(type default)
			)
			(layer "B.Fab")
		)
		(fp_line
			(start 0.12065 -0.2794)
			(end -0.12065 -0.2794)
			(stroke
				(width 0.1)
				(type default)
			)
			(layer "B.Fab")
		)
		(fp_line
			(start 0.12065 -0.305054)
			(end 0.12065 -0.2794)
			(stroke
				(width 0.1)
				(type default)
			)
			(layer "B.Fab")
		)
		(fp_line
			(start -0.120396 0.3048)
			(end -0.120396 0.2794)
			(stroke
				(width 0.1)
				(type default)
			)
			(layer "B.Fab")
		)
		(fp_line
			(start -0.120396 0.2794)
			(end 0.12065 0.2794)
			(stroke
				(width 0.1)
				(type default)
			)
			(layer "B.Fab")
		)
		(fp_line
			(start -0.12065 -0.2794)
			(end -0.12065 -0.3048)
			(stroke
				(width 0.1)
				(type default)
			)
			(layer "B.Fab")
		)
		(fp_line
			(start -0.12065 -0.3048)
			(end -0.67945 -0.3048)
			(stroke
				(width 0.1)
				(type default)
			)
			(layer "B.Fab")
		)
		(fp_line
			(start -0.67945 0.3048)
			(end -0.120396 0.3048)
			(stroke
				(width 0.1)
				(type default)
			)
			(layer "B.Fab")
		)
		(fp_line
			(start -0.67945 -0.3048)
			(end -0.67945 0.3048)
			(stroke
				(width 0.1)
				(type default)
			)
			(layer "B.Fab")
		)
		(pad "1" smd circle
			(at 0.40005 0)
			(size 0 0)
			(layers "B.Cu" "B.Mask" "B.Paste")
			(net "P3V3_AUX")
		)
		(pad "2" smd circle
			(at -0.40005 0)
			(size 0 0)
			(layers "B.Cu" "B.Mask" "B.Paste")
			(net "GND")
		)
	)
)
